(kicad_pcb
	(version 20260206)
	(generator "pcbnew")
	(generator_version "10.0")
	(general
		(thickness 1.6)
		(legacy_teardrops no)
	)
	(paper "A4")
	(title_block
		(title "04192023_DAF0TMB3IC0_F0TG_MB_C_brd_V02_OCP.brd")
		(comment 1 "Grand Teton / footprints 4703-4709 of 8354")
	)
	(layers
		(0 "F.Cu" signal "TOP")
		(4 "In1.Cu" signal "GND")
		(6 "In2.Cu" signal "IN1")
		(8 "In3.Cu" signal "GND1")
		(10 "In4.Cu" signal "IN2")
		(12 "In5.Cu" signal "GND2")
		(14 "In6.Cu" signal "IN3")
		(16 "In7.Cu" signal "GND3")
		(18 "In8.Cu" signal "VCC")
		(20 "In9.Cu" signal "VCC1")
		(22 "In10.Cu" signal "GND4")
		(24 "In11.Cu" signal "IN4")
		(26 "In12.Cu" signal "GND5")
		(28 "In13.Cu" signal "IN5")
		(30 "In14.Cu" signal "GND6")
		(32 "In15.Cu" signal "IN6")
		(34 "In16.Cu" signal "GND7")
		(2 "B.Cu" signal "BOTTOM")
		(9 "F.Adhes" user "F.Adhesive")
		(11 "B.Adhes" user "B.Adhesive")
		(13 "F.Paste" user "Package Geometry/Pastemask Top")
		(15 "B.Paste" user "Package Geometry/Pastemask Bottom")
		(5 "F.SilkS" user "Ref Des/Silkscreen Top")
		(7 "B.SilkS" user "Ref Des/Silkscreen Bottom")
		(1 "F.Mask" user "Board Geometry/Soldermask Top")
		(3 "B.Mask" user "Board Geometry/Soldermask Bottom")
		(17 "Dwgs.User" user "User.Drawings")
		(19 "Cmts.User" user "User.Comments")
		(21 "Eco1.User" user "User.Eco1")
		(23 "Eco2.User" user "User.Eco2")
		(25 "Edge.Cuts" user "Board Geometry/Outline")
		(27 "Margin" user)
		(31 "F.CrtYd" user "Package Geometry/Place Bound Top")
		(29 "B.CrtYd" user "Package Geometry/Place Bound Bottom")
		(35 "F.Fab" user "Ref Des/Assembly Top")
		(33 "B.Fab" user "Ref Des/Assembly Bottom")
	)
	(footprint ""
		(layer "F.Cu")
		(at 150.339044 -373.03583 -90)
		(property "Reference" "C762"
			(at 0 0 270)
			(layer "F.SilkS")
			(hide yes)
			(effects
				(font
					(size 1.27 1.27)
				)
			)
		)
		(property "Value" ""
			(at 0 0 270)
			(layer "F.Fab")
			(effects
				(font
					(size 1.27 1.27)
				)
			)
		)
		(duplicate_pad_numbers_are_jumpers no)
		(fp_line
			(start -0.299974 0.150114)
			(end -0.299974 -0.150114)
			(stroke
				(width 0.1)
				(type default)
			)
			(layer "F.Fab")
		)
		(fp_line
			(start 0.299974 0.150114)
			(end -0.299974 0.150114)
			(stroke
				(width 0.1)
				(type default)
			)
			(layer "F.Fab")
		)
		(fp_line
			(start -0.299974 -0.150114)
			(end 0.299974 -0.150114)
			(stroke
				(width 0.1)
				(type default)
			)
			(layer "F.Fab")
		)
		(fp_line
			(start 0.299974 -0.150114)
			(end 0.299974 0.150114)
			(stroke
				(width 0.1)
				(type default)
			)
			(layer "F.Fab")
		)
		(pad "1" smd rect
			(at -0.2667 0 270)
			(size 0.3048 0.381)
			(layers "F.Cu" "F.Mask" "F.Paste")
			(net "P5E_CPU1_P2_TX_C_DN<5>")
		)
		(pad "2" smd rect
			(at 0.2667 0 270)
			(size 0.3048 0.381)
			(layers "F.Cu" "F.Mask" "F.Paste")
			(net "P5E_CPU1_P2_TX_DN<5>")
		)
	)
	(footprint ""
		(layer "F.Cu")
		(at 16.645382 -105.56621 90)
		(property "Reference" "R2791"
			(at 0 0 90)
			(layer "F.SilkS")
			(hide yes)
			(effects
				(font
					(size 1.27 1.27)
				)
			)
		)
		(property "Value" ""
			(at 0 0 90)
			(layer "F.Fab")
			(effects
				(font
					(size 1.27 1.27)
				)
			)
		)
		(duplicate_pad_numbers_are_jumpers no)
		(fp_line
			(start 0.7874 -0.4064)
			(end 0.7874 0.4064)
			(stroke
				(width 0.1524)
				(type default)
			)
			(layer "F.SilkS")
		)
		(fp_line
			(start -0.7874 -0.4064)
			(end 0.7874 -0.4064)
			(stroke
				(width 0.1524)
				(type default)
			)
			(layer "F.SilkS")
		)
		(fp_line
			(start 0.7874 0.4064)
			(end -0.7874 0.4064)
			(stroke
				(width 0.1524)
				(type default)
			)
			(layer "F.SilkS")
		)
		(fp_line
			(start -0.7874 0.4064)
			(end -0.7874 -0.4064)
			(stroke
				(width 0.1524)
				(type default)
			)
			(layer "F.SilkS")
		)
		(fp_line
			(start -0.12065 -0.305054)
			(end -0.12065 -0.2794)
			(stroke
				(width 0.1)
				(type default)
			)
			(layer "F.Fab")
		)
		(fp_line
			(start -0.67945 -0.305054)
			(end -0.12065 -0.305054)
			(stroke
				(width 0.1)
				(type default)
			)
			(layer "F.Fab")
		)
		(fp_line
			(start 0.67945 -0.3048)
			(end 0.67945 0.3048)
			(stroke
				(width 0.1)
				(type default)
			)
			(layer "F.Fab")
		)
		(fp_line
			(start 0.12065 -0.3048)
			(end 0.67945 -0.3048)
			(stroke
				(width 0.1)
				(type default)
			)
			(layer "F.Fab")
		)
		(fp_line
			(start 0.12065 -0.2794)
			(end 0.12065 -0.3048)
			(stroke
				(width 0.1)
				(type default)
			)
			(layer "F.Fab")
		)
		(fp_line
			(start -0.12065 -0.2794)
			(end 0.12065 -0.2794)
			(stroke
				(width 0.1)
				(type default)
			)
			(layer "F.Fab")
		)
		(fp_line
			(start 0.120396 0.2794)
			(end -0.12065 0.2794)
			(stroke
				(width 0.1)
				(type default)
			)
			(layer "F.Fab")
		)
		(fp_line
			(start -0.12065 0.2794)
			(end -0.12065 0.3048)
			(stroke
				(width 0.1)
				(type default)
			)
			(layer "F.Fab")
		)
		(fp_line
			(start 0.67945 0.3048)
			(end 0.120396 0.3048)
			(stroke
				(width 0.1)
				(type default)
			)
			(layer "F.Fab")
		)
		(fp_line
			(start 0.120396 0.3048)
			(end 0.120396 0.2794)
			(stroke
				(width 0.1)
				(type default)
			)
			(layer "F.Fab")
		)
		(fp_line
			(start -0.12065 0.3048)
			(end -0.67945 0.3048)
			(stroke
				(width 0.1)
				(type default)
			)
			(layer "F.Fab")
		)
		(fp_line
			(start -0.67945 0.3048)
			(end -0.67945 -0.305054)
			(stroke
				(width 0.1)
				(type default)
			)
			(layer "F.Fab")
		)
		(pad "1" smd rect
			(at -0.40005 0 270)
			(size 0.4572 0.508)
			(layers "F.Cu" "F.Mask" "F.Paste")
			(net "USB2_HOST_BMC_B_DN")
		)
		(pad "2" smd rect
			(at 0.40005 0 270)
			(size 0.4572 0.508)
			(layers "F.Cu" "F.Mask" "F.Paste")
			(net "USB2_HOST_BMC_B_BUF_DN")
		)
	)
	(footprint ""
		(layer "F.Cu")
		(at 72.194928 -339.651848 -90)
		(property "Reference" "PC414"
			(at 0 0 270)
			(layer "F.SilkS")
			(hide yes)
			(effects
				(font
					(size 1.27 1.27)
				)
			)
		)
		(property "Value" ""
			(at 0 0 270)
			(layer "F.Fab")
			(effects
				(font
					(size 1.27 1.27)
				)
			)
		)
		(duplicate_pad_numbers_are_jumpers no)
		(fp_line
			(start -0.7874 0.4064)
			(end -0.7874 -0.4064)
			(stroke
				(width 0.1524)
				(type default)
			)
			(layer "F.SilkS")
		)
		(fp_line
			(start 0.7874 0.4064)
			(end -0.7874 0.4064)
			(stroke
				(width 0.1524)
				(type default)
			)
			(layer "F.SilkS")
		)
		(fp_line
			(start -0.7874 -0.4064)
			(end 0.7874 -0.4064)
			(stroke
				(width 0.1524)
				(type default)
			)
			(layer "F.SilkS")
		)
		(fp_line
			(start 0.7874 -0.4064)
			(end 0.7874 0.4064)
			(stroke
				(width 0.1524)
				(type default)
			)
			(layer "F.SilkS")
		)
		(fp_line
			(start -0.67945 0.3048)
			(end -0.67945 -0.305054)
			(stroke
				(width 0.1)
				(type default)
			)
			(layer "F.Fab")
		)
		(fp_line
			(start -0.12065 0.3048)
			(end -0.67945 0.3048)
			(stroke
				(width 0.1)
				(type default)
			)
			(layer "F.Fab")
		)
		(fp_line
			(start 0.120396 0.3048)
			(end 0.120396 0.2794)
			(stroke
				(width 0.1)
				(type default)
			)
			(layer "F.Fab")
		)
		(fp_line
			(start 0.67945 0.3048)
			(end 0.120396 0.3048)
			(stroke
				(width 0.1)
				(type default)
			)
			(layer "F.Fab")
		)
		(fp_line
			(start -0.12065 0.2794)
			(end -0.12065 0.3048)
			(stroke
				(width 0.1)
				(type default)
			)
			(layer "F.Fab")
		)
		(fp_line
			(start 0.120396 0.2794)
			(end -0.12065 0.2794)
			(stroke
				(width 0.1)
				(type default)
			)
			(layer "F.Fab")
		)
		(fp_line
			(start -0.12065 -0.2794)
			(end 0.12065 -0.2794)
			(stroke
				(width 0.1)
				(type default)
			)
			(layer "F.Fab")
		)
		(fp_line
			(start 0.12065 -0.2794)
			(end 0.12065 -0.3048)
			(stroke
				(width 0.1)
				(type default)
			)
			(layer "F.Fab")
		)
		(fp_line
			(start 0.12065 -0.3048)
			(end 0.67945 -0.3048)
			(stroke
				(width 0.1)
				(type default)
			)
			(layer "F.Fab")
		)
		(fp_line
			(start 0.67945 -0.3048)
			(end 0.67945 0.3048)
			(stroke
				(width 0.1)
				(type default)
			)
			(layer "F.Fab")
		)
		(fp_line
			(start -0.67945 -0.305054)
			(end -0.12065 -0.305054)
			(stroke
				(width 0.1)
				(type default)
			)
			(layer "F.Fab")
		)
		(fp_line
			(start -0.12065 -0.305054)
			(end -0.12065 -0.2794)
			(stroke
				(width 0.1)
				(type default)
			)
			(layer "F.Fab")
		)
		(pad "1" smd circle
			(at -0.40005 0 270)
			(size 0 0)
			(layers "F.Cu" "F.Mask" "F.Paste")
			(net "SW_PVDDCR_CPU1_P1_BOOT3_R")
		)
		(pad "2" smd circle
			(at 0.40005 0 270)
			(size 0 0)
			(layers "F.Cu" "F.Mask" "F.Paste")
			(net "SW_PVDDCR_CPU1_P1_BOOTR3")
		)
	)
	(footprint ""
		(layer "F.Cu")
		(at 439.821066 -389.9535)
		(property "Reference" "PR6532"
			(at 0 0 0)
			(layer "F.SilkS")
			(hide yes)
			(effects
				(font
					(size 1.27 1.27)
				)
			)
		)
		(property "Value" ""
			(at 0 0 0)
			(layer "F.Fab")
			(effects
				(font
					(size 1.27 1.27)
				)
			)
		)
		(duplicate_pad_numbers_are_jumpers no)
		(fp_line
			(start -0.7874 -0.4064)
			(end 0.7874 -0.4064)
			(stroke
				(width 0.1524)
				(type default)
			)
			(layer "F.SilkS")
		)
		(fp_line
			(start -0.7874 0.4064)
			(end -0.7874 -0.4064)
			(stroke
				(width 0.1524)
				(type default)
			)
			(layer "F.SilkS")
		)
		(fp_line
			(start 0.7874 -0.4064)
			(end 0.7874 0.4064)
			(stroke
				(width 0.1524)
				(type default)
			)
			(layer "F.SilkS")
		)
		(fp_line
			(start 0.7874 0.4064)
			(end -0.7874 0.4064)
			(stroke
				(width 0.1524)
				(type default)
			)
			(layer "F.SilkS")
		)
		(fp_line
			(start -0.67945 -0.305054)
			(end -0.12065 -0.305054)
			(stroke
				(width 0.1)
				(type default)
			)
			(layer "F.Fab")
		)
		(fp_line
			(start -0.67945 0.3048)
			(end -0.67945 -0.305054)
			(stroke
				(width 0.1)
				(type default)
			)
			(layer "F.Fab")
		)
		(fp_line
			(start -0.12065 -0.305054)
			(end -0.12065 -0.2794)
			(stroke
				(width 0.1)
				(type default)
			)
			(layer "F.Fab")
		)
		(fp_line
			(start -0.12065 -0.2794)
			(end 0.12065 -0.2794)
			(stroke
				(width 0.1)
				(type default)
			)
			(layer "F.Fab")
		)
		(fp_line
			(start -0.12065 0.2794)
			(end -0.12065 0.3048)
			(stroke
				(width 0.1)
				(type default)
			)
			(layer "F.Fab")
		)
		(fp_line
			(start -0.12065 0.3048)
			(end -0.67945 0.3048)
			(stroke
				(width 0.1)
				(type default)
			)
			(layer "F.Fab")
		)
		(fp_line
			(start 0.120396 0.2794)
			(end -0.12065 0.2794)
			(stroke
				(width 0.1)
				(type default)
			)
			(layer "F.Fab")
		)
		(fp_line
			(start 0.120396 0.3048)
			(end 0.120396 0.2794)
			(stroke
				(width 0.1)
				(type default)
			)
			(layer "F.Fab")
		)
		(fp_line
			(start 0.12065 -0.3048)
			(end 0.67945 -0.3048)
			(stroke
				(width 0.1)
				(type default)
			)
			(layer "F.Fab")
		)
		(fp_line
			(start 0.12065 -0.2794)
			(end 0.12065 -0.3048)
			(stroke
				(width 0.1)
				(type default)
			)
			(layer "F.Fab")
		)
		(fp_line
			(start 0.67945 -0.3048)
			(end 0.67945 0.3048)
			(stroke
				(width 0.1)
				(type default)
			)
			(layer "F.Fab")
		)
		(fp_line
			(start 0.67945 0.3048)
			(end 0.120396 0.3048)
			(stroke
				(width 0.1)
				(type default)
			)
			(layer "F.Fab")
		)
		(pad "1" smd circle
			(at -0.40005 0)
			(size 0 0)
			(layers "F.Cu" "F.Mask" "F.Paste")
			(net "P0V9_RETIMER_CPU0_SENSE_SH_N")
		)
		(pad "2" smd circle
			(at 0.40005 0)
			(size 0 0)
			(layers "F.Cu" "F.Mask" "F.Paste")
			(net "GND")
		)
	)
	(footprint ""
		(layer "F.Cu")
		(at 245.52275 -50.335434 180)
		(property "Reference" "R1283"
			(at 0 0 180)
			(layer "F.SilkS")
			(hide yes)
			(effects
				(font
					(size 1.27 1.27)
				)
			)
		)
		(property "Value" ""
			(at 0 0 180)
			(layer "F.Fab")
			(effects
				(font
					(size 1.27 1.27)
				)
			)
		)
		(duplicate_pad_numbers_are_jumpers no)
		(fp_line
			(start 0.7874 0.4064)
			(end -0.7874 0.4064)
			(stroke
				(width 0.1524)
				(type default)
			)
			(layer "F.SilkS")
		)
		(fp_line
			(start 0.7874 -0.4064)
			(end 0.7874 0.4064)
			(stroke
				(width 0.1524)
				(type default)
			)
			(layer "F.SilkS")
		)
		(fp_line
			(start -0.7874 0.4064)
			(end -0.7874 -0.4064)
			(stroke
				(width 0.1524)
				(type default)
			)
			(layer "F.SilkS")
		)
		(fp_line
			(start -0.7874 -0.4064)
			(end 0.7874 -0.4064)
			(stroke
				(width 0.1524)
				(type default)
			)
			(layer "F.SilkS")
		)
		(fp_line
			(start 0.67945 0.3048)
			(end 0.120396 0.3048)
			(stroke
				(width 0.1)
				(type default)
			)
			(layer "F.Fab")
		)
		(fp_line
			(start 0.67945 -0.3048)
			(end 0.67945 0.3048)
			(stroke
				(width 0.1)
				(type default)
			)
			(layer "F.Fab")
		)
		(fp_line
			(start 0.12065 -0.2794)
			(end 0.12065 -0.3048)
			(stroke
				(width 0.1)
				(type default)
			)
			(layer "F.Fab")
		)
		(fp_line
			(start 0.12065 -0.3048)
			(end 0.67945 -0.3048)
			(stroke
				(width 0.1)
				(type default)
			)
			(layer "F.Fab")
		)
		(fp_line
			(start 0.120396 0.3048)
			(end 0.120396 0.2794)
			(stroke
				(width 0.1)
				(type default)
			)
			(layer "F.Fab")
		)
		(fp_line
			(start 0.120396 0.2794)
			(end -0.12065 0.2794)
			(stroke
				(width 0.1)
				(type default)
			)
			(layer "F.Fab")
		)
		(fp_line
			(start -0.12065 0.3048)
			(end -0.67945 0.3048)
			(stroke
				(width 0.1)
				(type default)
			)
			(layer "F.Fab")
		)
		(fp_line
			(start -0.12065 0.2794)
			(end -0.12065 0.3048)
			(stroke
				(width 0.1)
				(type default)
			)
			(layer "F.Fab")
		)
		(fp_line
			(start -0.12065 -0.2794)
			(end 0.12065 -0.2794)
			(stroke
				(width 0.1)
				(type default)
			)
			(layer "F.Fab")
		)
		(fp_line
			(start -0.12065 -0.305054)
			(end -0.12065 -0.2794)
			(stroke
				(width 0.1)
				(type default)
			)
			(layer "F.Fab")
		)
		(fp_line
			(start -0.67945 0.3048)
			(end -0.67945 -0.305054)
			(stroke
				(width 0.1)
				(type default)
			)
			(layer "F.Fab")
		)
		(fp_line
			(start -0.67945 -0.305054)
			(end -0.12065 -0.305054)
			(stroke
				(width 0.1)
				(type default)
			)
			(layer "F.Fab")
		)
		(pad "1" smd circle
			(at -0.40005 0 180)
			(size 0 0)
			(layers "F.Cu" "F.Mask" "F.Paste")
			(net "P12V_E1S_0")
		)
		(pad "2" smd circle
			(at 0.40005 0 180)
			(size 0 0)
			(layers "F.Cu" "F.Mask" "F.Paste")
			(net "VSENSE_P12V_INA230_8_INP")
		)
	)
	(footprint ""
		(layer "F.Cu")
		(at 399.171668 -395.066774 -90)
		(property "Reference" "R631"
			(at 0 0 270)
			(layer "F.SilkS")
			(hide yes)
			(effects
				(font
					(size 1.27 1.27)
				)
			)
		)
		(property "Value" ""
			(at 0 0 270)
			(layer "F.Fab")
			(effects
				(font
					(size 1.27 1.27)
				)
			)
		)
		(duplicate_pad_numbers_are_jumpers no)
		(fp_line
			(start -0.32512 0.175006)
			(end -0.32512 -0.175006)
			(stroke
				(width 0.1)
				(type default)
			)
			(layer "F.Fab")
		)
		(fp_line
			(start 0.32512 0.175006)
			(end -0.32512 0.175006)
			(stroke
				(width 0.1)
				(type default)
			)
			(layer "F.Fab")
		)
		(fp_line
			(start -0.32512 -0.175006)
			(end 0.32512 -0.175006)
			(stroke
				(width 0.1)
				(type default)
			)
			(layer "F.Fab")
		)
		(fp_line
			(start 0.32512 -0.175006)
			(end 0.32512 0.175006)
			(stroke
				(width 0.1)
				(type default)
			)
			(layer "F.Fab")
		)
		(pad "1" smd rect
			(at -0.2667 0 270)
			(size 0.3048 0.381)
			(layers "F.Cu" "F.Mask" "F.Paste")
			(net "CLK_100M_RETIMER_CPU0_P2_DN")
		)
		(pad "2" smd rect
			(at 0.2667 0 90)
			(size 0.3048 0.381)
			(layers "F.Cu" "F.Mask" "F.Paste")
			(net "GND")
		)
	)
	(footprint ""
		(layer "F.Cu")
		(at 64.614298 -24.798782 180)
		(property "Reference" "PC1320"
			(at 0 0 180)
			(layer "F.SilkS")
			(hide yes)
			(effects
				(font
					(size 1.27 1.27)
				)
			)
		)
		(property "Value" ""
			(at 0 0 180)
			(layer "F.Fab")
			(effects
				(font
					(size 1.27 1.27)
				)
			)
		)
		(duplicate_pad_numbers_are_jumpers no)
		(fp_line
			(start 1.2954 0.5842)
			(end -1.2954 0.5842)
			(stroke
				(width 0.1524)
				(type default)
			)
			(layer "F.SilkS")
		)
		(fp_line
			(start 1.2954 -0.5842)
			(end 1.2954 0.5842)
			(stroke
				(width 0.1524)
				(type default)
			)
			(layer "F.SilkS")
		)
		(fp_line
			(start -1.2954 0.5842)
			(end -1.2954 -0.5842)
			(stroke
				(width 0.1524)
				(type default)
			)
			(layer "F.SilkS")
		)
		(fp_line
			(start -1.2954 -0.5842)
			(end 1.2954 -0.5842)
			(stroke
				(width 0.1524)
				(type default)
			)
			(layer "F.SilkS")
		)
		(fp_line
			(start 1.1938 0.4064)
			(end 0.8636 0.4064)
			(stroke
				(width 0.1)
				(type default)
			)
			(layer "F.Fab")
		)
		(fp_line
			(start 1.1938 -0.4064)
			(end 1.1938 0.4064)
			(stroke
				(width 0.1)
				(type default)
			)
			(layer "F.Fab")
		)
		(fp_line
			(start 0.8636 0.4572)
			(end -0.8636 0.4572)
			(stroke
				(width 0.1)
				(type default)
			)
			(layer "F.Fab")
		)
		(fp_line
			(start 0.8636 0.4064)
			(end 0.8636 0.4572)
			(stroke
				(width 0.1)
				(type default)
			)
			(layer "F.Fab")
		)
		(fp_line
			(start 0.8636 -0.4064)
			(end 1.1938 -0.4064)
			(stroke
				(width 0.1)
				(type default)
			)
			(layer "F.Fab")
		)
		(fp_line
			(start 0.8636 -0.4572)
			(end 0.8636 -0.4064)
			(stroke
				(width 0.1)
				(type default)
			)
			(layer "F.Fab")
		)
		(fp_line
			(start -0.8636 0.4572)
			(end -0.8636 0.4064)
			(stroke
				(width 0.1)
				(type default)
			)
			(layer "F.Fab")
		)
		(fp_line
			(start -0.8636 0.4064)
			(end -1.1938 0.4064)
			(stroke
				(width 0.1)
				(type default)
			)
			(layer "F.Fab")
		)
		(fp_line
			(start -0.8636 -0.4064)
			(end -0.8636 -0.4572)
			(stroke
				(width 0.1)
				(type default)
			)
			(layer "F.Fab")
		)
		(fp_line
			(start -0.8636 -0.4572)
			(end 0.8636 -0.4572)
			(stroke
				(width 0.1)
				(type default)
			)
			(layer "F.Fab")
		)
		(fp_line
			(start -1.1938 0.4064)
			(end -1.1938 -0.4064)
			(stroke
				(width 0.1)
				(type default)
			)
			(layer "F.Fab")
		)
		(fp_line
			(start -1.1938 -0.4064)
			(end -0.8636 -0.4064)
			(stroke
				(width 0.1)
				(type default)
			)
			(layer "F.Fab")
		)
		(pad "1" smd rect
			(at -0.7366 0 90)
			(size 0.7112 0.8128)
			(layers "F.Cu" "F.Mask" "F.Paste")
			(net "P12V_OCP_AVIN_PD_2")
		)
		(pad "2" smd rect
			(at 0.7366 0 90)
			(size 0.7112 0.8128)
			(layers "F.Cu" "F.Mask" "F.Paste")
			(net "GND")
		)
	)
)
